(kicad_pcb
	(version 20260206)
	(generator "pcbnew")
	(generator_version "10.0")
	(general
		(thickness 1.6)
		(legacy_teardrops no)
	)
	(paper "A4")
	(title_block
		(title "01162023_DA0F0TEBIF0_F0T_Expander_BD_F_brd_V02_OCP.brd")
		(comment 1 "Grand Teton / footprints 6179-6185 of 9728")
	)
	(layers
		(0 "F.Cu" signal "TOP")
		(4 "In1.Cu" signal "GND")
		(6 "In2.Cu" signal "VCC")
		(8 "In3.Cu" signal "VCC1")
		(10 "In4.Cu" signal "GND1")
		(12 "In5.Cu" signal "IN1")
		(14 "In6.Cu" signal "GND2")
		(16 "In7.Cu" signal "IN2")
		(18 "In8.Cu" signal "GND3")
		(20 "In9.Cu" signal "IN3")
		(22 "In10.Cu" signal "GND4")
		(24 "In11.Cu" signal "IN4")
		(26 "In12.Cu" signal "GND5")
		(28 "In13.Cu" signal "IN5")
		(30 "In14.Cu" signal "GND6")
		(32 "In15.Cu" signal "IN6")
		(34 "In16.Cu" signal "GND7")
		(2 "B.Cu" signal "BOTTOM")
		(9 "F.Adhes" user "F.Adhesive")
		(11 "B.Adhes" user "B.Adhesive")
		(13 "F.Paste" user "Package Geometry/Pastemask Top")
		(15 "B.Paste" user "Package Geometry/Pastemask Bottom")
		(5 "F.SilkS" user "Ref Des/Silkscreen Top")
		(7 "B.SilkS" user "Ref Des/Silkscreen Bottom")
		(1 "F.Mask" user "Board Geometry/Soldermask Top")
		(3 "B.Mask" user "Board Geometry/Soldermask Bottom")
		(17 "Dwgs.User" user "User.Drawings")
		(19 "Cmts.User" user "User.Comments")
		(21 "Eco1.User" user "User.Eco1")
		(23 "Eco2.User" user "User.Eco2")
		(25 "Edge.Cuts" user "Board Geometry/Outline")
		(27 "Margin" user)
		(31 "F.CrtYd" user "Package Geometry/Place Bound Top")
		(29 "B.CrtYd" user "Package Geometry/Place Bound Bottom")
		(35 "F.Fab" user "Ref Des/Assembly Top")
		(33 "B.Fab" user "Ref Des/Assembly Bottom")
	)
	(footprint ""
		(layer "F.Cu")
		(at 113.561114 -262.703564 180)
		(property "Reference" "PR82"
			(at 0 0 180)
			(layer "F.SilkS")
			(hide yes)
			(effects
				(font
					(size 1.27 1.27)
				)
			)
		)
		(property "Value" ""
			(at 0 0 180)
			(layer "F.Fab")
			(effects
				(font
					(size 1.27 1.27)
				)
			)
		)
		(duplicate_pad_numbers_are_jumpers no)
		(fp_line
			(start 0.7874 0.4064)
			(end -0.7874 0.4064)
			(stroke
				(width 0.1524)
				(type default)
			)
			(layer "F.SilkS")
		)
		(fp_line
			(start 0.7874 -0.4064)
			(end 0.7874 0.4064)
			(stroke
				(width 0.1524)
				(type default)
			)
			(layer "F.SilkS")
		)
		(fp_line
			(start -0.7874 0.4064)
			(end -0.7874 -0.4064)
			(stroke
				(width 0.1524)
				(type default)
			)
			(layer "F.SilkS")
		)
		(fp_line
			(start -0.7874 -0.4064)
			(end 0.7874 -0.4064)
			(stroke
				(width 0.1524)
				(type default)
			)
			(layer "F.SilkS")
		)
		(fp_line
			(start 0.67945 0.3048)
			(end 0.120396 0.3048)
			(stroke
				(width 0.1)
				(type default)
			)
			(layer "F.Fab")
		)
		(fp_line
			(start 0.67945 -0.3048)
			(end 0.67945 0.3048)
			(stroke
				(width 0.1)
				(type default)
			)
			(layer "F.Fab")
		)
		(fp_line
			(start 0.12065 -0.2794)
			(end 0.12065 -0.3048)
			(stroke
				(width 0.1)
				(type default)
			)
			(layer "F.Fab")
		)
		(fp_line
			(start 0.12065 -0.3048)
			(end 0.67945 -0.3048)
			(stroke
				(width 0.1)
				(type default)
			)
			(layer "F.Fab")
		)
		(fp_line
			(start 0.120396 0.3048)
			(end 0.120396 0.2794)
			(stroke
				(width 0.1)
				(type default)
			)
			(layer "F.Fab")
		)
		(fp_line
			(start 0.120396 0.2794)
			(end -0.12065 0.2794)
			(stroke
				(width 0.1)
				(type default)
			)
			(layer "F.Fab")
		)
		(fp_line
			(start -0.12065 0.3048)
			(end -0.67945 0.3048)
			(stroke
				(width 0.1)
				(type default)
			)
			(layer "F.Fab")
		)
		(fp_line
			(start -0.12065 0.2794)
			(end -0.12065 0.3048)
			(stroke
				(width 0.1)
				(type default)
			)
			(layer "F.Fab")
		)
		(fp_line
			(start -0.12065 -0.2794)
			(end 0.12065 -0.2794)
			(stroke
				(width 0.1)
				(type default)
			)
			(layer "F.Fab")
		)
		(fp_line
			(start -0.12065 -0.305054)
			(end -0.12065 -0.2794)
			(stroke
				(width 0.1)
				(type default)
			)
			(layer "F.Fab")
		)
		(fp_line
			(start -0.67945 0.3048)
			(end -0.67945 -0.305054)
			(stroke
				(width 0.1)
				(type default)
			)
			(layer "F.Fab")
		)
		(fp_line
			(start -0.67945 -0.305054)
			(end -0.12065 -0.305054)
			(stroke
				(width 0.1)
				(type default)
			)
			(layer "F.Fab")
		)
		(pad "1" smd circle
			(at -0.40005 0 180)
			(size 0 0)
			(layers "F.Cu" "F.Mask" "F.Paste")
			(net "P0V8_PEX0_VR_CONFIG")
		)
		(pad "2" smd circle
			(at 0.40005 0 180)
			(size 0 0)
			(layers "F.Cu" "F.Mask" "F.Paste")
			(net "P3V3_AUX")
		)
	)
	(footprint ""
		(layer "F.Cu")
		(at 327.82256 -22.867366 90)
		(property "Reference" "C3952"
			(at 0 0 90)
			(layer "F.SilkS")
			(hide yes)
			(effects
				(font
					(size 1.27 1.27)
				)
			)
		)
		(property "Value" ""
			(at 0 0 90)
			(layer "F.Fab")
			(effects
				(font
					(size 1.27 1.27)
				)
			)
		)
		(duplicate_pad_numbers_are_jumpers no)
		(fp_line
			(start 0.7874 -0.4064)
			(end 0.7874 0.4064)
			(stroke
				(width 0.1524)
				(type default)
			)
			(layer "F.SilkS")
		)
		(fp_line
			(start -0.7874 -0.4064)
			(end 0.7874 -0.4064)
			(stroke
				(width 0.1524)
				(type default)
			)
			(layer "F.SilkS")
		)
		(fp_line
			(start 0.7874 0.4064)
			(end -0.7874 0.4064)
			(stroke
				(width 0.1524)
				(type default)
			)
			(layer "F.SilkS")
		)
		(fp_line
			(start -0.7874 0.4064)
			(end -0.7874 -0.4064)
			(stroke
				(width 0.1524)
				(type default)
			)
			(layer "F.SilkS")
		)
		(fp_line
			(start -0.12065 -0.305054)
			(end -0.12065 -0.2794)
			(stroke
				(width 0.1)
				(type default)
			)
			(layer "F.Fab")
		)
		(fp_line
			(start -0.67945 -0.305054)
			(end -0.12065 -0.305054)
			(stroke
				(width 0.1)
				(type default)
			)
			(layer "F.Fab")
		)
		(fp_line
			(start 0.67945 -0.3048)
			(end 0.67945 0.3048)
			(stroke
				(width 0.1)
				(type default)
			)
			(layer "F.Fab")
		)
		(fp_line
			(start 0.12065 -0.3048)
			(end 0.67945 -0.3048)
			(stroke
				(width 0.1)
				(type default)
			)
			(layer "F.Fab")
		)
		(fp_line
			(start 0.12065 -0.2794)
			(end 0.12065 -0.3048)
			(stroke
				(width 0.1)
				(type default)
			)
			(layer "F.Fab")
		)
		(fp_line
			(start -0.12065 -0.2794)
			(end 0.12065 -0.2794)
			(stroke
				(width 0.1)
				(type default)
			)
			(layer "F.Fab")
		)
		(fp_line
			(start 0.120396 0.2794)
			(end -0.12065 0.2794)
			(stroke
				(width 0.1)
				(type default)
			)
			(layer "F.Fab")
		)
		(fp_line
			(start -0.12065 0.2794)
			(end -0.12065 0.3048)
			(stroke
				(width 0.1)
				(type default)
			)
			(layer "F.Fab")
		)
		(fp_line
			(start 0.67945 0.3048)
			(end 0.120396 0.3048)
			(stroke
				(width 0.1)
				(type default)
			)
			(layer "F.Fab")
		)
		(fp_line
			(start 0.120396 0.3048)
			(end 0.120396 0.2794)
			(stroke
				(width 0.1)
				(type default)
			)
			(layer "F.Fab")
		)
		(fp_line
			(start -0.12065 0.3048)
			(end -0.67945 0.3048)
			(stroke
				(width 0.1)
				(type default)
			)
			(layer "F.Fab")
		)
		(fp_line
			(start -0.67945 0.3048)
			(end -0.67945 -0.305054)
			(stroke
				(width 0.1)
				(type default)
			)
			(layer "F.Fab")
		)
		(pad "1" smd circle
			(at -0.40005 0 90)
			(size 0 0)
			(layers "F.Cu" "F.Mask" "F.Paste")
			(net "P12V_SSD11")
		)
		(pad "2" smd circle
			(at 0.40005 0 90)
			(size 0 0)
			(layers "F.Cu" "F.Mask" "F.Paste")
			(net "GND")
		)
	)
	(footprint ""
		(layer "F.Cu")
		(at 268.838426 -134.923276)
		(property "Reference" "C458"
			(at 0 0 0)
			(layer "F.SilkS")
			(hide yes)
			(effects
				(font
					(size 1.27 1.27)
				)
			)
		)
		(property "Value" ""
			(at 0 0 0)
			(layer "F.Fab")
			(effects
				(font
					(size 1.27 1.27)
				)
			)
		)
		(duplicate_pad_numbers_are_jumpers no)
		(fp_line
			(start -0.299974 -0.150114)
			(end 0.299974 -0.150114)
			(stroke
				(width 0.1)
				(type default)
			)
			(layer "F.Fab")
		)
		(fp_line
			(start -0.299974 0.150114)
			(end -0.299974 -0.150114)
			(stroke
				(width 0.1)
				(type default)
			)
			(layer "F.Fab")
		)
		(fp_line
			(start 0.299974 -0.150114)
			(end 0.299974 0.150114)
			(stroke
				(width 0.1)
				(type default)
			)
			(layer "F.Fab")
		)
		(fp_line
			(start 0.299974 0.150114)
			(end -0.299974 0.150114)
			(stroke
				(width 0.1)
				(type default)
			)
			(layer "F.Fab")
		)
		(pad "1" smd rect
			(at -0.2667 0)
			(size 0.3048 0.381)
			(layers "F.Cu" "F.Mask" "F.Paste")
			(net "P5E_PEX2_STN1_TX_DN<30>")
		)
		(pad "2" smd rect
			(at 0.2667 0)
			(size 0.3048 0.381)
			(layers "F.Cu" "F.Mask" "F.Paste")
			(net "P5E_PEX2_STN1_TX_C_DN<30>")
		)
	)
	(footprint ""
		(layer "F.Cu")
		(at 47.885604 -25.1587 -90)
		(property "Reference" "R5734"
			(at 0 0 270)
			(layer "F.SilkS")
			(hide yes)
			(effects
				(font
					(size 1.27 1.27)
				)
			)
		)
		(property "Value" ""
			(at 0 0 270)
			(layer "F.Fab")
			(effects
				(font
					(size 1.27 1.27)
				)
			)
		)
		(duplicate_pad_numbers_are_jumpers no)
		(fp_line
			(start -0.7874 0.4064)
			(end -0.7874 -0.4064)
			(stroke
				(width 0.1524)
				(type default)
			)
			(layer "F.SilkS")
		)
		(fp_line
			(start 0.7874 0.4064)
			(end -0.7874 0.4064)
			(stroke
				(width 0.1524)
				(type default)
			)
			(layer "F.SilkS")
		)
		(fp_line
			(start -0.7874 -0.4064)
			(end 0.7874 -0.4064)
			(stroke
				(width 0.1524)
				(type default)
			)
			(layer "F.SilkS")
		)
		(fp_line
			(start 0.7874 -0.4064)
			(end 0.7874 0.4064)
			(stroke
				(width 0.1524)
				(type default)
			)
			(layer "F.SilkS")
		)
		(fp_line
			(start -0.67945 0.3048)
			(end -0.67945 -0.305054)
			(stroke
				(width 0.1)
				(type default)
			)
			(layer "F.Fab")
		)
		(fp_line
			(start -0.12065 0.3048)
			(end -0.67945 0.3048)
			(stroke
				(width 0.1)
				(type default)
			)
			(layer "F.Fab")
		)
		(fp_line
			(start 0.120396 0.3048)
			(end 0.120396 0.2794)
			(stroke
				(width 0.1)
				(type default)
			)
			(layer "F.Fab")
		)
		(fp_line
			(start 0.67945 0.3048)
			(end 0.120396 0.3048)
			(stroke
				(width 0.1)
				(type default)
			)
			(layer "F.Fab")
		)
		(fp_line
			(start -0.12065 0.2794)
			(end -0.12065 0.3048)
			(stroke
				(width 0.1)
				(type default)
			)
			(layer "F.Fab")
		)
		(fp_line
			(start 0.120396 0.2794)
			(end -0.12065 0.2794)
			(stroke
				(width 0.1)
				(type default)
			)
			(layer "F.Fab")
		)
		(fp_line
			(start -0.12065 -0.2794)
			(end 0.12065 -0.2794)
			(stroke
				(width 0.1)
				(type default)
			)
			(layer "F.Fab")
		)
		(fp_line
			(start 0.12065 -0.2794)
			(end 0.12065 -0.3048)
			(stroke
				(width 0.1)
				(type default)
			)
			(layer "F.Fab")
		)
		(fp_line
			(start 0.12065 -0.3048)
			(end 0.67945 -0.3048)
			(stroke
				(width 0.1)
				(type default)
			)
			(layer "F.Fab")
		)
		(fp_line
			(start 0.67945 -0.3048)
			(end 0.67945 0.3048)
			(stroke
				(width 0.1)
				(type default)
			)
			(layer "F.Fab")
		)
		(fp_line
			(start -0.67945 -0.305054)
			(end -0.12065 -0.305054)
			(stroke
				(width 0.1)
				(type default)
			)
			(layer "F.Fab")
		)
		(fp_line
			(start -0.12065 -0.305054)
			(end -0.12065 -0.2794)
			(stroke
				(width 0.1)
				(type default)
			)
			(layer "F.Fab")
		)
		(pad "1" smd circle
			(at -0.40005 0 270)
			(size 0 0)
			(layers "F.Cu" "F.Mask" "F.Paste")
			(net "SSD1_LED_ISO_N")
		)
		(pad "2" smd circle
			(at 0.40005 0 270)
			(size 0 0)
			(layers "F.Cu" "F.Mask" "F.Paste")
			(net "SSD1_LED_ISO_R_N")
		)
	)
	(footprint ""
		(layer "F.Cu")
		(at 108.441236 -303.649634 90)
		(property "Reference" "PC69"
			(at 0 0 90)
			(layer "F.SilkS")
			(hide yes)
			(effects
				(font
					(size 1.27 1.27)
				)
			)
		)
		(property "Value" ""
			(at 0 0 90)
			(layer "F.Fab")
			(effects
				(font
					(size 1.27 1.27)
				)
			)
		)
		(duplicate_pad_numbers_are_jumpers no)
		(fp_line
			(start 1.524 -0.762)
			(end 1.524 0.762)
			(stroke
				(width 0.1524)
				(type default)
			)
			(layer "F.SilkS")
		)
		(fp_line
			(start -1.524 -0.762)
			(end 1.524 -0.762)
			(stroke
				(width 0.1524)
				(type default)
			)
			(layer "F.SilkS")
		)
		(fp_line
			(start 1.524 0.762)
			(end -1.524 0.762)
			(stroke
				(width 0.1524)
				(type default)
			)
			(layer "F.SilkS")
		)
		(fp_line
			(start -1.524 0.762)
			(end -1.524 -0.762)
			(stroke
				(width 0.1524)
				(type default)
			)
			(layer "F.SilkS")
		)
		(fp_line
			(start 1.1049 -0.724916)
			(end -1.1049 -0.724916)
			(stroke
				(width 0.1)
				(type default)
			)
			(layer "F.Fab")
		)
		(fp_line
			(start -1.1049 -0.724916)
			(end -1.1049 0.724916)
			(stroke
				(width 0.1)
				(type default)
			)
			(layer "F.Fab")
		)
		(fp_line
			(start 1.1049 0.724916)
			(end 1.1049 -0.724916)
			(stroke
				(width 0.1)
				(type default)
			)
			(layer "F.Fab")
		)
		(fp_line
			(start -1.1049 0.724916)
			(end 1.1049 0.724916)
			(stroke
				(width 0.1)
				(type default)
			)
			(layer "F.Fab")
		)
		(pad "1" smd rect
			(at -0.889 0 270)
			(size 1.016 1.27)
			(layers "F.Cu" "F.Mask" "F.Paste")
			(net "P0V8_PEX0")
		)
		(pad "2" smd rect
			(at 0.889 0 270)
			(size 1.016 1.27)
			(layers "F.Cu" "F.Mask" "F.Paste")
			(net "GND")
		)
	)
	(footprint ""
		(layer "F.Cu")
		(at 349.907098 -282.421584 -90)
		(property "Reference" "PC155"
			(at 0 0 270)
			(layer "F.SilkS")
			(hide yes)
			(effects
				(font
					(size 1.27 1.27)
				)
			)
		)
		(property "Value" ""
			(at 0 0 270)
			(layer "F.Fab")
			(effects
				(font
					(size 1.27 1.27)
				)
			)
		)
		(duplicate_pad_numbers_are_jumpers no)
		(fp_line
			(start -0.7874 0.4064)
			(end -0.7874 -0.4064)
			(stroke
				(width 0.1524)
				(type default)
			)
			(layer "F.SilkS")
		)
		(fp_line
			(start 0.7874 0.4064)
			(end -0.7874 0.4064)
			(stroke
				(width 0.1524)
				(type default)
			)
			(layer "F.SilkS")
		)
		(fp_line
			(start -0.7874 -0.4064)
			(end 0.7874 -0.4064)
			(stroke
				(width 0.1524)
				(type default)
			)
			(layer "F.SilkS")
		)
		(fp_line
			(start 0.7874 -0.4064)
			(end 0.7874 0.4064)
			(stroke
				(width 0.1524)
				(type default)
			)
			(layer "F.SilkS")
		)
		(fp_line
			(start -0.67945 0.3048)
			(end -0.67945 -0.305054)
			(stroke
				(width 0.1)
				(type default)
			)
			(layer "F.Fab")
		)
		(fp_line
			(start -0.12065 0.3048)
			(end -0.67945 0.3048)
			(stroke
				(width 0.1)
				(type default)
			)
			(layer "F.Fab")
		)
		(fp_line
			(start 0.120396 0.3048)
			(end 0.120396 0.2794)
			(stroke
				(width 0.1)
				(type default)
			)
			(layer "F.Fab")
		)
		(fp_line
			(start 0.67945 0.3048)
			(end 0.120396 0.3048)
			(stroke
				(width 0.1)
				(type default)
			)
			(layer "F.Fab")
		)
		(fp_line
			(start -0.12065 0.2794)
			(end -0.12065 0.3048)
			(stroke
				(width 0.1)
				(type default)
			)
			(layer "F.Fab")
		)
		(fp_line
			(start 0.120396 0.2794)
			(end -0.12065 0.2794)
			(stroke
				(width 0.1)
				(type default)
			)
			(layer "F.Fab")
		)
		(fp_line
			(start -0.12065 -0.2794)
			(end 0.12065 -0.2794)
			(stroke
				(width 0.1)
				(type default)
			)
			(layer "F.Fab")
		)
		(fp_line
			(start 0.12065 -0.2794)
			(end 0.12065 -0.3048)
			(stroke
				(width 0.1)
				(type default)
			)
			(layer "F.Fab")
		)
		(fp_line
			(start 0.12065 -0.3048)
			(end 0.67945 -0.3048)
			(stroke
				(width 0.1)
				(type default)
			)
			(layer "F.Fab")
		)
		(fp_line
			(start 0.67945 -0.3048)
			(end 0.67945 0.3048)
			(stroke
				(width 0.1)
				(type default)
			)
			(layer "F.Fab")
		)
		(fp_line
			(start -0.67945 -0.305054)
			(end -0.12065 -0.305054)
			(stroke
				(width 0.1)
				(type default)
			)
			(layer "F.Fab")
		)
		(fp_line
			(start -0.12065 -0.305054)
			(end -0.12065 -0.2794)
			(stroke
				(width 0.1)
				(type default)
			)
			(layer "F.Fab")
		)
		(pad "1" smd circle
			(at -0.40005 0 270)
			(size 0 0)
			(layers "F.Cu" "F.Mask" "F.Paste")
			(net "P0V8_PEX2_VCC2")
		)
		(pad "2" smd circle
			(at 0.40005 0 270)
			(size 0 0)
			(layers "F.Cu" "F.Mask" "F.Paste")
			(net "GND")
		)
	)
	(footprint ""
		(layer "F.Cu")
		(at 4.51866 -380.182628)
		(property "Reference" "C4459"
			(at 0 0 0)
			(layer "F.SilkS")
			(hide yes)
			(effects
				(font
					(size 1.27 1.27)
				)
			)
		)
		(property "Value" ""
			(at 0 0 0)
			(layer "F.Fab")
			(effects
				(font
					(size 1.27 1.27)
				)
			)
		)
		(duplicate_pad_numbers_are_jumpers no)
		(fp_line
			(start -0.7874 -0.4064)
			(end 0.7874 -0.4064)
			(stroke
				(width 0.1524)
				(type default)
			)
			(layer "F.SilkS")
		)
		(fp_line
			(start -0.7874 0.4064)
			(end -0.7874 -0.4064)
			(stroke
				(width 0.1524)
				(type default)
			)
			(layer "F.SilkS")
		)
		(fp_line
			(start 0.7874 -0.4064)
			(end 0.7874 0.4064)
			(stroke
				(width 0.1524)
				(type default)
			)
			(layer "F.SilkS")
		)
		(fp_line
			(start 0.7874 0.4064)
			(end -0.7874 0.4064)
			(stroke
				(width 0.1524)
				(type default)
			)
			(layer "F.SilkS")
		)
		(fp_line
			(start -0.67945 -0.305054)
			(end -0.12065 -0.305054)
			(stroke
				(width 0.1)
				(type default)
			)
			(layer "F.Fab")
		)
		(fp_line
			(start -0.67945 0.3048)
			(end -0.67945 -0.305054)
			(stroke
				(width 0.1)
				(type default)
			)
			(layer "F.Fab")
		)
		(fp_line
			(start -0.12065 -0.305054)
			(end -0.12065 -0.2794)
			(stroke
				(width 0.1)
				(type default)
			)
			(layer "F.Fab")
		)
		(fp_line
			(start -0.12065 -0.2794)
			(end 0.12065 -0.2794)
			(stroke
				(width 0.1)
				(type default)
			)
			(layer "F.Fab")
		)
		(fp_line
			(start -0.12065 0.2794)
			(end -0.12065 0.3048)
			(stroke
				(width 0.1)
				(type default)
			)
			(layer "F.Fab")
		)
		(fp_line
			(start -0.12065 0.3048)
			(end -0.67945 0.3048)
			(stroke
				(width 0.1)
				(type default)
			)
			(layer "F.Fab")
		)
		(fp_line
			(start 0.120396 0.2794)
			(end -0.12065 0.2794)
			(stroke
				(width 0.1)
				(type default)
			)
			(layer "F.Fab")
		)
		(fp_line
			(start 0.120396 0.3048)
			(end 0.120396 0.2794)
			(stroke
				(width 0.1)
				(type default)
			)
			(layer "F.Fab")
		)
		(fp_line
			(start 0.12065 -0.3048)
			(end 0.67945 -0.3048)
			(stroke
				(width 0.1)
				(type default)
			)
			(layer "F.Fab")
		)
		(fp_line
			(start 0.12065 -0.2794)
			(end 0.12065 -0.3048)
			(stroke
				(width 0.1)
				(type default)
			)
			(layer "F.Fab")
		)
		(fp_line
			(start 0.67945 -0.3048)
			(end 0.67945 0.3048)
			(stroke
				(width 0.1)
				(type default)
			)
			(layer "F.Fab")
		)
		(fp_line
			(start 0.67945 0.3048)
			(end 0.120396 0.3048)
			(stroke
				(width 0.1)
				(type default)
			)
			(layer "F.Fab")
		)
		(pad "1" smd circle
			(at -0.40005 0)
			(size 0 0)
			(layers "F.Cu" "F.Mask" "F.Paste")
			(net "BIC_USB_8042_HUB_XIN")
		)
		(pad "2" smd circle
			(at 0.40005 0)
			(size 0 0)
			(layers "F.Cu" "F.Mask" "F.Paste")
			(net "GND")
		)
	)
)
